(kicad_pcb
	(version 20241229)
	(generator "pcbnew")
	(generator_version "9.0")
	(general
		(thickness 1.63)
		(legacy_teardrops no)
	)
	(paper "A4")
	(title_block
		(title "CM4 Baseboard")
		(date "2026-01-05")
		(rev "1.1.1")
		(company "Antmicro Ltd")
		(comment 1 "www.antmicro.com")
		(comment 9 "footprints 25-30 of 506")
	)
	(layers
		(0 "F.Cu" signal)
		(4 "In1.Cu" power)
		(6 "In2.Cu" power)
		(8 "In3.Cu" signal)
		(10 "In4.Cu" signal)
		(2 "B.Cu" signal)
		(9 "F.Adhes" user "F.Adhesive")
		(11 "B.Adhes" user "B.Adhesive")
		(13 "F.Paste" user)
		(15 "B.Paste" user)
		(5 "F.SilkS" user "F.Silkscreen")
		(7 "B.SilkS" user "B.Silkscreen")
		(1 "F.Mask" user)
		(3 "B.Mask" user)
		(17 "Dwgs.User" user "User.Drawings")
		(19 "Cmts.User" user "User.Comments")
		(21 "Eco1.User" user "User.Eco1")
		(23 "Eco2.User" user "User.Eco2")
		(25 "Edge.Cuts" user)
		(27 "Margin" user)
		(31 "F.CrtYd" user "F.Courtyard")
		(29 "B.CrtYd" user "B.Courtyard")
		(35 "F.Fab" user)
		(33 "B.Fab" user)
	)
	(footprint "antmicro-footprints:TP_SMD_0.75mm"
		(layer "F.Cu")
		(at 118.15 127.25 180)
		(property "Reference" "TP504"
			(at -3.85 -0.5 0)
			(layer "F.SilkS")
			(effects
				(font
					(size 0.7 0.7)
					(thickness 0.15)
				)
				(justify right bottom)
			)
		)
		(property "Value" "TP_0.75mm_SMD"
			(at 0 1.2 0)
			(layer "F.Fab")
			(effects
				(font
					(size 0.7 0.7)
					(thickness 0.15)
				)
				(justify right bottom)
			)
		)
		(property "MPN" ""
			(at 0 0 180)
			(unlocked yes)
			(layer "F.Fab")
			(hide yes)
			(effects
				(font
					(size 1 1)
					(thickness 0.15)
				)
			)
		)
		(property "Manufacturer" ""
			(at 0 0 180)
			(unlocked yes)
			(layer "F.Fab")
			(hide yes)
			(effects
				(font
					(size 1 1)
					(thickness 0.15)
				)
			)
		)
		(property "Author" "Antmicro"
			(at 0 0 180)
			(unlocked yes)
			(layer "F.Fab")
			(hide yes)
			(effects
				(font
					(size 1 1)
					(thickness 0.15)
				)
			)
		)
		(property "License" "Apache-2.0"
			(at 0 0 180)
			(unlocked yes)
			(layer "F.Fab")
			(hide yes)
			(effects
				(font
					(size 1 1)
					(thickness 0.15)
				)
			)
		)
		(sheetname "/NVMe & microSD/")
		(sheetfile "nvme-micro-sd.kicad_sch")
		(attr exclude_from_pos_files exclude_from_bom)
		(fp_circle
			(center 0 0)
			(end 0.475 0)
			(stroke
				(width 0.05)
				(type default)
			)
			(fill no)
			(layer "F.CrtYd")
		)
		(fp_text user "Author: Antmicro"
			(at -0.4 3.901 180)
			(layer "F.Fab")
			(effects
				(font
					(size 0.7 0.7)
					(thickness 0.15)
				)
				(justify left bottom)
			)
		)
		(fp_text user "${REFERENCE}"
			(at -0.4 2.7 180)
			(layer "F.Fab")
			(effects
				(font
					(size 0.7 0.7)
					(thickness 0.15)
				)
				(justify left bottom)
			)
		)
		(fp_text user "License: Apache-2.0"
			(at -0.4 5.101 180)
			(layer "F.Fab")
			(effects
				(font
					(size 0.7 0.7)
					(thickness 0.15)
				)
				(justify left bottom)
			)
		)
		(pad "1" smd circle
			(at 0 0 180)
			(size 0.75 0.75)
			(layers "F.Cu" "F.Mask")
			(net 193 "Net-(J501-SMB_CLK)")
			(pinfunction "1")
			(pintype "passive")
		)
	)
	(footprint "antmicro-footprints:R_0402_1005Metric"
		(layer "F.Cu")
		(at 123.805476 165.9665)
		(descr "Resistor SMD 0402")
		(tags "resistor SMD 0402")
		(property "Reference" "R508"
			(at -3.837514 0.39 0)
			(layer "F.SilkS")
			(effects
				(font
					(size 0.7 0.7)
					(thickness 0.15)
				)
				(justify left bottom)
			)
		)
		(property "Value" "R_10k_0402"
			(at -1.011843 1.772047 0)
			(layer "F.Fab")
			(effects
				(font
					(size 0.7 0.7)
					(thickness 0.15)
				)
				(justify left bottom)
			)
		)
		(property "Datasheet" "https://www.bourns.com/docs/product-datasheets/cr.pdf"
			(at 0 0 0)
			(layer "F.Fab")
			(hide yes)
			(effects
				(font
					(size 1.27 1.27)
					(thickness 0.15)
				)
			)
		)
		(property "Manufacturer" "Bourns"
			(at 0 0 0)
			(unlocked yes)
			(layer "F.Fab")
			(hide yes)
			(effects
				(font
					(size 1 1)
					(thickness 0.15)
				)
			)
		)
		(property "MPN" "CR0402-FX-1002GLF"
			(at 0 0 0)
			(unlocked yes)
			(layer "F.Fab")
			(hide yes)
			(effects
				(font
					(size 1 1)
					(thickness 0.15)
				)
			)
		)
		(property "Val" "10k"
			(at 0 0 0)
			(unlocked yes)
			(layer "F.Fab")
			(hide yes)
			(effects
				(font
					(size 1 1)
					(thickness 0.15)
				)
			)
		)
		(property "License" "Apache-2.0"
			(at 0 0 0)
			(unlocked yes)
			(layer "F.Fab")
			(hide yes)
			(effects
				(font
					(size 1 1)
					(thickness 0.15)
				)
			)
		)
		(property "Author" "Antmicro"
			(at 0 0 0)
			(unlocked yes)
			(layer "F.Fab")
			(hide yes)
			(effects
				(font
					(size 1 1)
					(thickness 0.15)
				)
			)
		)
		(property "Tolerance" "1%"
			(at 0 0 0)
			(unlocked yes)
			(layer "F.Fab")
			(hide yes)
			(effects
				(font
					(size 1 1)
					(thickness 0.15)
				)
			)
		)
		(sheetname "/NVMe & microSD/")
		(sheetfile "nvme-micro-sd.kicad_sch")
		(attr smd)
		(fp_rect
			(start -0.925 -0.47)
			(end 0.925 0.47)
			(stroke
				(width 0.05)
				(type default)
			)
			(fill no)
			(layer "F.CrtYd")
		)
		(fp_rect
			(start -0.5 -0.25)
			(end 0.5 0.25)
			(stroke
				(width 0.15)
				(type solid)
			)
			(fill no)
			(layer "F.Fab")
		)
		(fp_text user "License: Apache-2.0"
			(at -0.95 5.169 0)
			(layer "F.Fab")
			(effects
				(font
					(size 0.7 0.7)
					(thickness 0.15)
				)
				(justify left bottom)
			)
		)
		(fp_text user "${REFERENCE}"
			(at -0.95 3.168 0)
			(layer "F.Fab")
			(effects
				(font
					(size 0.7 0.7)
					(thickness 0.15)
				)
				(justify left bottom)
			)
		)
		(fp_text user "Author: Antmicro"
			(at -0.95 4.169 0)
			(layer "F.Fab")
			(effects
				(font
					(size 0.7 0.7)
					(thickness 0.15)
				)
				(justify left bottom)
			)
		)
		(pad "1" smd roundrect
			(at -0.48 0)
			(size 0.59 0.64)
			(layers "F.Cu" "F.Mask" "F.Paste")
			(roundrect_rratio 0.25)
			(net 9 "+3V3")
			(pintype "passive")
		)
		(pad "2" smd roundrect
			(at 0.48 0)
			(size 0.59 0.64)
			(layers "F.Cu" "F.Mask" "F.Paste")
			(roundrect_rratio 0.25)
			(net 8 "/Compute module/SDIO.CMD")
			(pintype "passive")
		)
	)
	(footprint "antmicro-footprints:R_0402_1005Metric"
		(layer "F.Cu")
		(at 72.867962 166.4365 180)
		(descr "Resistor SMD 0402")
		(tags "resistor SMD 0402")
		(property "Reference" "R805"
			(at -0.962038 1.43 0)
			(layer "F.SilkS")
			(effects
				(font
					(size 0.7 0.7)
					(thickness 0.15)
				)
				(justify right bottom)
			)
		)
		(property "Value" "R_10k_0402"
			(at -1.011843 1.772047 0)
			(layer "F.Fab")
			(effects
				(font
					(size 0.7 0.7)
					(thickness 0.15)
				)
				(justify right bottom)
			)
		)
		(property "Datasheet" "https://www.bourns.com/docs/product-datasheets/cr.pdf"
			(at 0 0 180)
			(layer "F.Fab")
			(hide yes)
			(effects
				(font
					(size 1.27 1.27)
					(thickness 0.15)
				)
			)
		)
		(property "MPN" "CR0402-FX-1002GLF"
			(at 0 0 180)
			(unlocked yes)
			(layer "F.Fab")
			(hide yes)
			(effects
				(font
					(size 1 1)
					(thickness 0.15)
				)
			)
		)
		(property "Manufacturer" "Bourns"
			(at 0 0 180)
			(unlocked yes)
			(layer "F.Fab")
			(hide yes)
			(effects
				(font
					(size 1 1)
					(thickness 0.15)
				)
			)
		)
		(property "License" "Apache-2.0"
			(at 0 0 180)
			(unlocked yes)
			(layer "F.Fab")
			(hide yes)
			(effects
				(font
					(size 1 1)
					(thickness 0.15)
				)
			)
		)
		(property "Author" "Antmicro"
			(at 0 0 180)
			(unlocked yes)
			(layer "F.Fab")
			(hide yes)
			(effects
				(font
					(size 1 1)
					(thickness 0.15)
				)
			)
		)
		(property "Val" "10k"
			(at 0 0 180)
			(unlocked yes)
			(layer "F.Fab")
			(hide yes)
			(effects
				(font
					(size 1 1)
					(thickness 0.15)
				)
			)
		)
		(property "Tolerance" "1%"
			(at 0 0 180)
			(unlocked yes)
			(layer "F.Fab")
			(hide yes)
			(effects
				(font
					(size 1 1)
					(thickness 0.15)
				)
			)
		)
		(sheetname "/Peripherals/")
		(sheetfile "peripherals.kicad_sch")
		(attr smd exclude_from_pos_files exclude_from_bom dnp)
		(fp_rect
			(start -0.925 -0.47)
			(end 0.925 0.47)
			(stroke
				(width 0.05)
				(type default)
			)
			(fill no)
			(layer "F.CrtYd")
		)
		(fp_rect
			(start -0.5 -0.25)
			(end 0.5 0.25)
			(stroke
				(width 0.15)
				(type solid)
			)
			(fill no)
			(layer "F.Fab")
		)
		(fp_text user "License: Apache-2.0"
			(at -0.95 5.169 180)
			(layer "F.Fab")
			(effects
				(font
					(size 0.7 0.7)
					(thickness 0.15)
				)
				(justify left bottom)
			)
		)
		(fp_text user "Author: Antmicro"
			(at -0.95 4.169 180)
			(layer "F.Fab")
			(effects
				(font
					(size 0.7 0.7)
					(thickness 0.15)
				)
				(justify left bottom)
			)
		)
		(fp_text user "${REFERENCE}"
			(at -0.95 3.168 180)
			(layer "F.Fab")
			(effects
				(font
					(size 0.7 0.7)
					(thickness 0.15)
				)
				(justify left bottom)
			)
		)
		(pad "1" smd roundrect
			(at -0.48 0 180)
			(size 0.59 0.64)
			(layers "F.Cu" "F.Mask" "F.Paste")
			(roundrect_rratio 0.25)
			(net 375 "Net-(U801-I2C_ADR1)")
			(pintype "passive")
		)
		(pad "2" smd roundrect
			(at 0.48 0 180)
			(size 0.59 0.64)
			(layers "F.Cu" "F.Mask" "F.Paste")
			(roundrect_rratio 0.25)
			(net 9 "+3V3")
			(pintype "passive")
		)
	)
	(footprint "antmicro-footprints:SW_KMR211NGLFS_SMD"
		(layer "F.Cu")
		(at 136.042962 122.6915 -90)
		(property "Reference" "S201"
			(at 3.4085 0.767962 0)
			(layer "F.SilkS")
			(effects
				(font
					(size 0.7 0.7)
					(thickness 0.15)
				)
				(justify left bottom)
			)
		)
		(property "Value" "SW_KMR211NGLFS_SMD"
			(at 0 2.8 90)
			(layer "F.Fab")
			(effects
				(font
					(size 0.7 0.7)
					(thickness 0.15)
				)
				(justify right bottom)
			)
		)
		(property "Datasheet" "http://www.farnell.com/datasheets/2631211.pdf"
			(at 0 0 270)
			(layer "F.Fab")
			(hide yes)
			(effects
				(font
					(size 1.27 1.27)
					(thickness 0.15)
				)
			)
		)
		(property "MPN" "KMR211NGLFS"
			(at 0 0 270)
			(unlocked yes)
			(layer "F.Fab")
			(hide yes)
			(effects
				(font
					(size 1 1)
					(thickness 0.15)
				)
			)
		)
		(property "Manufacturer" "C&K"
			(at 0 0 270)
			(unlocked yes)
			(layer "F.Fab")
			(hide yes)
			(effects
				(font
					(size 1 1)
					(thickness 0.15)
				)
			)
		)
		(property "Author" "Antmicro"
			(at 0 0 270)
			(unlocked yes)
			(layer "F.Fab")
			(hide yes)
			(effects
				(font
					(size 1 1)
					(thickness 0.15)
				)
			)
		)
		(property "License" "Apache-2.0"
			(at 0 0 270)
			(unlocked yes)
			(layer "F.Fab")
			(hide yes)
			(effects
				(font
					(size 1 1)
					(thickness 0.15)
				)
			)
		)
		(sheetname "/Compute module/")
		(sheetfile "compute-module.kicad_sch")
		(attr smd)
		(fp_line
			(start -2.1 1.601)
			(end -2.1 1.48)
			(stroke
				(width 0.15)
				(type solid)
			)
			(layer "F.SilkS")
		)
		(fp_line
			(start 2.101 1.601)
			(end -2.1 1.601)
			(stroke
				(width 0.15)
				(type solid)
			)
			(layer "F.SilkS")
		)
		(fp_line
			(start 2.101 1.601)
			(end 2.101 1.48)
			(stroke
				(width 0.15)
				(type solid)
			)
			(layer "F.SilkS")
		)
		(fp_line
			(start 2.101 -1.58)
			(end 2.101 -1.459)
			(stroke
				(width 0.15)
				(type solid)
			)
			(layer "F.SilkS")
		)
		(fp_line
			(start -2.1 -1.6)
			(end -2.1 -1.499)
			(stroke
				(width 0.15)
				(type solid)
			)
			(layer "F.SilkS")
		)
		(fp_line
			(start 2.101 -1.6)
			(end -2.1 -1.6)
			(stroke
				(width 0.15)
				(type solid)
			)
			(layer "F.SilkS")
		)
		(fp_rect
			(start 2.751 1.75)
			(end -2.748 -1.749)
			(stroke
				(width 0.05)
				(type solid)
			)
			(fill no)
			(layer "F.CrtYd")
		)
		(fp_line
			(start -2.1 1.601)
			(end 2.101 1.601)
			(stroke
				(width 0.15)
				(type solid)
			)
			(layer "F.Fab")
		)
		(fp_line
			(start 2.101 1.601)
			(end 2.101 -1.6)
			(stroke
				(width 0.15)
				(type solid)
			)
			(layer "F.Fab")
		)
		(fp_line
			(start 0.25 0.802)
			(end -0.248 0.802)
			(stroke
				(width 0.15)
				(type solid)
			)
			(layer "F.Fab")
		)
		(fp_line
			(start -0.248 -0.8)
			(end 0.25 -0.8)
			(stroke
				(width 0.15)
				(type solid)
			)
			(layer "F.Fab")
		)
		(fp_line
			(start -2.1 -1.6)
			(end -2.1 1.601)
			(stroke
				(width 0.15)
				(type solid)
			)
			(layer "F.Fab")
		)
		(fp_line
			(start 2.101 -1.6)
			(end -2.1 -1.6)
			(stroke
				(width 0.15)
				(type solid)
			)
			(layer "F.Fab")
		)
		(fp_arc
			(start -0.248 0.802)
			(mid -1.050001 0.001)
			(end -0.248 -0.8)
			(stroke
				(width 0.15)
				(type solid)
			)
			(layer "F.Fab")
		)
		(fp_arc
			(start 0.25 -0.8)
			(mid 1.051001 0.001)
			(end 0.25 0.802)
			(stroke
				(width 0.15)
				(type solid)
			)
			(layer "F.Fab")
		)
		(fp_text user "${REFERENCE}"
			(at -3 4.25 270)
			(layer "F.Fab")
			(effects
				(font
					(size 0.7 0.7)
					(thickness 0.15)
				)
				(justify left bottom)
			)
		)
		(fp_text user "Author: Antmicro"
			(at -3 5.5 270)
			(layer "F.Fab")
			(effects
				(font
					(size 0.7 0.7)
					(thickness 0.15)
				)
				(justify left bottom)
			)
		)
		(fp_text user "License: Apache-2.0"
			(at -3 6.75 270)
			(layer "F.Fab")
			(effects
				(font
					(size 0.7 0.7)
					(thickness 0.15)
				)
				(justify left bottom)
			)
		)
		(pad "1" smd rect
			(at -2.048 -0.8 90)
			(size 0.9 1)
			(layers "F.Cu" "F.Mask" "F.Paste")
			(net 9 "+3V3")
			(pinfunction "1")
			(pintype "passive")
		)
		(pad "2" smd rect
			(at 2.05 -0.8 90)
			(size 0.9 1)
			(layers "F.Cu" "F.Mask" "F.Paste")
			(net 9 "+3V3")
			(pinfunction "2")
			(pintype "passive")
		)
		(pad "3" smd rect
			(at -2.048 0.802 90)
			(size 0.9 1)
			(layers "F.Cu" "F.Mask" "F.Paste")
			(net 2 "Net-(D203-A)")
			(pinfunction "3")
			(pintype "passive")
		)
		(pad "4" smd rect
			(at 2.05 0.802 90)
			(size 0.9 1)
			(layers "F.Cu" "F.Mask" "F.Paste")
			(net 2 "Net-(D203-A)")
			(pinfunction "4")
			(pintype "passive")
		)
	)
	(footprint "antmicro-footprints:TP_SMD_0.75mm"
		(layer "F.Cu")
		(at 76.742962 164.6915 180)
		(property "Reference" "TP209"
			(at 8.975 0.575 0)
			(layer "F.SilkS")
			(effects
				(font
					(size 0.7 0.7)
					(thickness 0.15)
				)
				(justify right bottom)
			)
		)
		(property "Value" "TP_0.75mm_SMD"
			(at 0 1.2 0)
			(layer "F.Fab")
			(effects
				(font
					(size 0.7 0.7)
					(thickness 0.15)
				)
				(justify right bottom)
			)
		)
		(property "Author" "Antmicro"
			(at 0 0 180)
			(unlocked yes)
			(layer "F.Fab")
			(hide yes)
			(effects
				(font
					(size 1 1)
					(thickness 0.15)
				)
			)
		)
		(property "License" "Apache-2.0"
			(at 0 0 180)
			(unlocked yes)
			(layer "F.Fab")
			(hide yes)
			(effects
				(font
					(size 1 1)
					(thickness 0.15)
				)
			)
		)
		(property "MPN" ""
			(at 0 0 180)
			(unlocked yes)
			(layer "F.Fab")
			(hide yes)
			(effects
				(font
					(size 1 1)
					(thickness 0.15)
				)
			)
		)
		(property "Manufacturer" ""
			(at 0 0 180)
			(unlocked yes)
			(layer "F.Fab")
			(hide yes)
			(effects
				(font
					(size 1 1)
					(thickness 0.15)
				)
			)
		)
		(sheetname "/Compute module/")
		(sheetfile "compute-module.kicad_sch")
		(attr exclude_from_pos_files exclude_from_bom)
		(fp_circle
			(center 0 0)
			(end 0.475 0)
			(stroke
				(width 0.05)
				(type default)
			)
			(fill no)
			(layer "F.CrtYd")
		)
		(fp_text user "Author: Antmicro"
			(at -0.4 3.901 180)
			(layer "F.Fab")
			(effects
				(font
					(size 0.7 0.7)
					(thickness 0.15)
				)
				(justify left bottom)
			)
		)
		(fp_text user "${REFERENCE}"
			(at -0.4 2.7 180)
			(layer "F.Fab")
			(effects
				(font
					(size 0.7 0.7)
					(thickness 0.15)
				)
				(justify left bottom)
			)
		)
		(fp_text user "License: Apache-2.0"
			(at -0.4 5.101 180)
			(layer "F.Fab")
			(effects
				(font
					(size 0.7 0.7)
					(thickness 0.15)
				)
				(justify left bottom)
			)
		)
		(pad "1" smd circle
			(at 0 0 180)
			(size 0.75 0.75)
			(layers "F.Cu" "F.Mask")
			(net 254 "/Compute module/CAM_GPIO")
			(pinfunction "1")
			(pintype "passive")
		)
	)
	(footprint "antmicro-footprints:C_0402_1005Metric"
		(layer "F.Cu")
		(at 71.742962 176.5165 -90)
		(descr "Capacitor SMD 0402")
		(tags "capacitor SMD 0402")
		(property "Reference" "C805"
			(at -1.3165 0.492962 270)
			(layer "F.SilkS")
			(effects
				(font
					(size 0.7 0.7)
					(thickness 0.15)
				)
				(justify right bottom)
			)
		)
		(property "Value" "C_2u2_0402"
			(at -1.022927 2.155213 90)
			(layer "F.Fab")
			(effects
				(font
					(size 0.7 0.7)
					(thickness 0.15)
				)
				(justify right bottom)
			)
		)
		(property "Datasheet" "https://product.tdk.com/en/search/capacitor/ceramic/mlcc/info?part_no=C1005X5R1A225K050BC"
			(at 0 0 270)
			(layer "F.Fab")
			(hide yes)
			(effects
				(font
					(size 1.27 1.27)
					(thickness 0.15)
				)
			)
		)
		(property "MPN" "C1005X5R1A225K050BC"
			(at 0 0 270)
			(unlocked yes)
			(layer "F.Fab")
			(hide yes)
			(effects
				(font
					(size 1 1)
					(thickness 0.15)
				)
			)
		)
		(property "Manufacturer" "TDK"
			(at 0 0 270)
			(unlocked yes)
			(layer "F.Fab")
			(hide yes)
			(effects
				(font
					(size 1 1)
					(thickness 0.15)
				)
			)
		)
		(property "License" "Apache-2.0"
			(at 0 0 270)
			(unlocked yes)
			(layer "F.Fab")
			(hide yes)
			(effects
				(font
					(size 1 1)
					(thickness 0.15)
				)
			)
		)
		(property "Author" "Antmicro"
			(at 0 0 270)
			(unlocked yes)
			(layer "F.Fab")
			(hide yes)
			(effects
				(font
					(size 1 1)
					(thickness 0.15)
				)
			)
		)
		(property "Val" "2u2"
			(at 0 0 270)
			(unlocked yes)
			(layer "F.Fab")
			(hide yes)
			(effects
				(font
					(size 1 1)
					(thickness 0.15)
				)
			)
		)
		(property "Voltage" ""
			(at 0 0 270)
			(unlocked yes)
			(layer "F.Fab")
			(hide yes)
			(effects
				(font
					(size 1 1)
					(thickness 0.15)
				)
			)
		)
		(property "Dielectric" ""
			(at 0 0 270)
			(unlocked yes)
			(layer "F.Fab")
			(hide yes)
			(effects
				(font
					(size 1 1)
					(thickness 0.15)
				)
			)
		)
		(sheetname "/Peripherals/")
		(sheetfile "peripherals.kicad_sch")
		(attr smd)
		(fp_rect
			(start -0.925 -0.47)
			(end 0.925 0.47)
			(stroke
				(width 0.05)
				(type default)
			)
			(fill no)
			(layer "F.CrtYd")
		)
		(fp_line
			(start -0.494 0.248)
			(end -0.494 -0.25)
			(stroke
				(width 0.15)
				(type solid)
			)
			(layer "F.Fab")
		)
		(fp_line
			(start 0.504 0.248)
			(end -0.494 0.248)
			(stroke
				(width 0.15)
				(type solid)
			)
			(layer "F.Fab")
		)
		(fp_line
			(start -0.494 -0.25)
			(end 0.504 -0.25)
			(stroke
				(width 0.15)
				(type solid)
			)
			(layer "F.Fab")
		)
		(fp_line
			(start 0.504 -0.25)
			(end 0.504 0.248)
			(stroke
				(width 0.15)
				(type solid)
			)
			(layer "F.Fab")
		)
		(fp_text user "Author: Antmicro"
			(at -0.939 3.399 270)
			(layer "F.Fab")
			(effects
				(font
					(size 0.7 0.7)
					(thickness 0.15)
				)
				(justify left bottom)
			)
		)
		(fp_text user "${REFERENCE}"
			(at -0.939 4.599 270)
			(layer "F.Fab")
			(effects
				(font
					(size 0.7 0.7)
					(thickness 0.15)
				)
				(justify left bottom)
			)
		)
		(fp_text user "License: Apache-2.0"
			(at -0.939 5.799 270)
			(layer "F.Fab")
			(effects
				(font
					(size 0.7 0.7)
					(thickness 0.15)
				)
				(justify left bottom)
			)
		)
		(pad "1" smd roundrect
			(at -0.48 0 270)
			(size 0.59 0.64)
			(layers "F.Cu" "F.Mask" "F.Paste")
			(roundrect_rratio 0.25)
			(net 93 "Net-(U801-V_{DD(A)})")
			(pintype "passive")
		)
		(pad "2" smd roundrect
			(at 0.48 0 270)
			(size 0.59 0.64)
			(layers "F.Cu" "F.Mask" "F.Paste")
			(roundrect_rratio 0.25)
			(net 3 "GND")
			(pintype "passive")
		)
	)
)
